(kicad_pcb
	(version 20260206)
	(generator "pcbnew")
	(generator_version "10.0")
	(general
		(thickness 1.6)
		(legacy_teardrops no)
	)
	(paper "A4")
	(title_block
		(title "04192023_DAF0TMB3IC0_F0TG_MB_C_brd_V02_OCP.brd")
		(comment 1 "Grand Teton / footprint 802 of 8354 (J68), pads 114-226 of 291")
	)
	(layers
		(0 "F.Cu" signal "TOP")
		(4 "In1.Cu" signal "GND")
		(6 "In2.Cu" signal "IN1")
		(8 "In3.Cu" signal "GND1")
		(10 "In4.Cu" signal "IN2")
		(12 "In5.Cu" signal "GND2")
		(14 "In6.Cu" signal "IN3")
		(16 "In7.Cu" signal "GND3")
		(18 "In8.Cu" signal "VCC")
		(20 "In9.Cu" signal "VCC1")
		(22 "In10.Cu" signal "GND4")
		(24 "In11.Cu" signal "IN4")
		(26 "In12.Cu" signal "GND5")
		(28 "In13.Cu" signal "IN5")
		(30 "In14.Cu" signal "GND6")
		(32 "In15.Cu" signal "IN6")
		(34 "In16.Cu" signal "GND7")
		(2 "B.Cu" signal "BOTTOM")
		(9 "F.Adhes" user "F.Adhesive")
		(11 "B.Adhes" user "B.Adhesive")
		(13 "F.Paste" user "Package Geometry/Pastemask Top")
		(15 "B.Paste" user "Package Geometry/Pastemask Bottom")
		(5 "F.SilkS" user "Ref Des/Silkscreen Top")
		(7 "B.SilkS" user "Ref Des/Silkscreen Bottom")
		(1 "F.Mask" user "Board Geometry/Soldermask Top")
		(3 "B.Mask" user "Board Geometry/Soldermask Bottom")
		(17 "Dwgs.User" user "User.Drawings")
		(19 "Cmts.User" user "User.Comments")
		(21 "Eco1.User" user "User.Eco1")
		(23 "Eco2.User" user "User.Eco2")
		(25 "Edge.Cuts" user "Board Geometry/Outline")
		(27 "Margin" user)
		(31 "F.CrtYd" user "Package Geometry/Place Bound Top")
		(29 "B.CrtYd" user "Package Geometry/Place Bound Bottom")
		(35 "F.Fab" user "Ref Des/Assembly Top")
		(33 "B.Fab" user "Ref Des/Assembly Bottom")
	)
	(footprint ""
		(layer "F.Cu")
		(at 437.05018 -255.560068 180)
		(property "Reference" "J68"
			(at 1.32334 -81.844388 0)
			(unlocked yes)
			(layer "F.SilkS")
			(effects
				(font
					(size 0.7874 0.5842)
					(thickness 0.1524)
				)
			)
		)
		(property "Value" ""
			(at 0 0 180)
			(layer "F.Fab")
			(effects
				(font
					(size 1.27 1.27)
				)
			)
		)
		(duplicate_pad_numbers_are_jumpers no)
		(pad "114" smd rect
			(at -2.050034 37.824918 90)
			(size 0.519938 1.4986)
			(layers "F.Cu" "F.Mask" "F.Paste")
			(net "GND")
		)
		(pad "115" smd rect
			(at -2.050034 38.675056 90)
			(size 0.519938 1.4986)
			(layers "F.Cu" "F.Mask" "F.Paste")
			(net "M_J_CPU0_SB_DQS_DP<1>")
		)
		(pad "116" smd rect
			(at -2.050034 39.52494 90)
			(size 0.519938 1.4986)
			(layers "F.Cu" "F.Mask" "F.Paste")
			(net "M_J_CPU0_SB_DQS_DN<1>")
		)
		(pad "117" smd rect
			(at -2.050034 40.375078 90)
			(size 0.519938 1.4986)
			(layers "F.Cu" "F.Mask" "F.Paste")
			(net "GND")
		)
		(pad "118" smd rect
			(at -2.050034 41.224962 90)
			(size 0.519938 1.4986)
			(layers "F.Cu" "F.Mask" "F.Paste")
			(net "M_J_CPU0_SB_DQ<12>")
		)
		(pad "119" smd rect
			(at -2.050034 42.0751 90)
			(size 0.519938 1.4986)
			(layers "F.Cu" "F.Mask" "F.Paste")
			(net "GND")
		)
		(pad "120" smd rect
			(at -2.050034 42.924984 90)
			(size 0.519938 1.4986)
			(layers "F.Cu" "F.Mask" "F.Paste")
			(net "M_J_CPU0_SB_DQ<13>")
		)
		(pad "121" smd rect
			(at -2.050034 43.775122 90)
			(size 0.519938 1.4986)
			(layers "F.Cu" "F.Mask" "F.Paste")
			(net "GND")
		)
		(pad "122" smd rect
			(at -2.050034 44.625006 90)
			(size 0.519938 1.4986)
			(layers "F.Cu" "F.Mask" "F.Paste")
			(net "M_J_CPU0_SB_DQ<16>")
		)
		(pad "123" smd rect
			(at -2.050034 45.47489 90)
			(size 0.519938 1.4986)
			(layers "F.Cu" "F.Mask" "F.Paste")
			(net "GND")
		)
		(pad "124" smd rect
			(at -2.050034 46.325028 90)
			(size 0.519938 1.4986)
			(layers "F.Cu" "F.Mask" "F.Paste")
			(net "M_J_CPU0_SB_DQ<17>")
		)
		(pad "125" smd rect
			(at -2.050034 47.174912 90)
			(size 0.519938 1.4986)
			(layers "F.Cu" "F.Mask" "F.Paste")
			(net "GND")
		)
		(pad "126" smd rect
			(at -2.050034 48.02505 90)
			(size 0.519938 1.4986)
			(layers "F.Cu" "F.Mask" "F.Paste")
			(net "M_J_CPU0_SB_DQS_DP<2>")
		)
		(pad "127" smd rect
			(at -2.050034 48.874934 90)
			(size 0.519938 1.4986)
			(layers "F.Cu" "F.Mask" "F.Paste")
			(net "M_J_CPU0_SB_DQS_DN<2>")
		)
		(pad "128" smd rect
			(at -2.050034 49.725072 90)
			(size 0.519938 1.4986)
			(layers "F.Cu" "F.Mask" "F.Paste")
			(net "GND")
		)
		(pad "129" smd rect
			(at -2.050034 50.574956 90)
			(size 0.519938 1.4986)
			(layers "F.Cu" "F.Mask" "F.Paste")
			(net "M_J_CPU0_SB_DQ<20>")
		)
		(pad "130" smd rect
			(at -2.050034 51.425094 90)
			(size 0.519938 1.4986)
			(layers "F.Cu" "F.Mask" "F.Paste")
			(net "GND")
		)
		(pad "131" smd rect
			(at -2.050034 52.274978 90)
			(size 0.519938 1.4986)
			(layers "F.Cu" "F.Mask" "F.Paste")
			(net "M_J_CPU0_SB_DQ<21>")
		)
		(pad "132" smd rect
			(at -2.050034 53.125116 90)
			(size 0.519938 1.4986)
			(layers "F.Cu" "F.Mask" "F.Paste")
			(net "GND")
		)
		(pad "133" smd rect
			(at -2.050034 53.975 90)
			(size 0.519938 1.4986)
			(layers "F.Cu" "F.Mask" "F.Paste")
			(net "M_J_CPU0_SB_DQ<24>")
		)
		(pad "134" smd rect
			(at -2.050034 54.824884 90)
			(size 0.519938 1.4986)
			(layers "F.Cu" "F.Mask" "F.Paste")
			(net "GND")
		)
		(pad "135" smd rect
			(at -2.050034 55.675022 90)
			(size 0.519938 1.4986)
			(layers "F.Cu" "F.Mask" "F.Paste")
			(net "M_J_CPU0_SB_DQ<25>")
		)
		(pad "136" smd rect
			(at -2.050034 56.524906 90)
			(size 0.519938 1.4986)
			(layers "F.Cu" "F.Mask" "F.Paste")
			(net "GND")
		)
		(pad "137" smd rect
			(at -2.050034 57.375044 90)
			(size 0.519938 1.4986)
			(layers "F.Cu" "F.Mask" "F.Paste")
			(net "M_J_CPU0_SB_DQS_DP<3>")
		)
		(pad "138" smd rect
			(at -2.050034 58.224928 90)
			(size 0.519938 1.4986)
			(layers "F.Cu" "F.Mask" "F.Paste")
			(net "M_J_CPU0_SB_DQS_DN<3>")
		)
		(pad "139" smd rect
			(at -2.050034 59.075066 90)
			(size 0.519938 1.4986)
			(layers "F.Cu" "F.Mask" "F.Paste")
			(net "GND")
		)
		(pad "140" smd rect
			(at -2.050034 59.92495 90)
			(size 0.519938 1.4986)
			(layers "F.Cu" "F.Mask" "F.Paste")
			(net "M_J_CPU0_SB_DQ<28>")
		)
		(pad "141" smd rect
			(at -2.050034 60.775088 90)
			(size 0.519938 1.4986)
			(layers "F.Cu" "F.Mask" "F.Paste")
			(net "GND")
		)
		(pad "142" smd rect
			(at -2.050034 61.624972 90)
			(size 0.519938 1.4986)
			(layers "F.Cu" "F.Mask" "F.Paste")
			(net "M_J_CPU0_SB_DQ<29>")
		)
		(pad "143" smd rect
			(at -2.050034 62.47511 90)
			(size 0.519938 1.4986)
			(layers "F.Cu" "F.Mask" "F.Paste")
			(net "GND")
		)
		(pad "144" smd rect
			(at -2.050034 63.324994 90)
			(size 0.519938 1.4986)
			(layers "F.Cu" "F.Mask" "F.Paste")
			(net "Net_2376")
		)
		(pad "145" smd rect
			(at 2.050034 -63.324994 90)
			(size 0.519938 1.4986)
			(layers "F.Cu" "F.Mask" "F.Paste")
			(net "P12V_MEM_CPU0")
		)
		(pad "146" smd rect
			(at 2.050034 -62.47511 90)
			(size 0.519938 1.4986)
			(layers "F.Cu" "F.Mask" "F.Paste")
			(net "P12V_MEM_CPU0")
		)
		(pad "147" smd rect
			(at 2.050034 -61.624972 90)
			(size 0.519938 1.4986)
			(layers "F.Cu" "F.Mask" "F.Paste")
			(net "PWRGD_CHJ_CPU0_DIMM")
		)
		(pad "148" smd rect
			(at 2.050034 -60.775088 90)
			(size 0.519938 1.4986)
			(layers "F.Cu" "F.Mask" "F.Paste")
			(net "PD_CHJ_CPU0_DIMM_SAA")
		)
		(pad "149" smd rect
			(at 2.050034 -59.92495 90)
			(size 0.519938 1.4986)
			(layers "F.Cu" "F.Mask" "F.Paste")
			(net "Net_2377")
		)
		(pad "150" smd rect
			(at 2.050034 -59.075066 90)
			(size 0.519938 1.4986)
			(layers "F.Cu" "F.Mask" "F.Paste")
			(net "Net_2378")
		)
		(pad "151" smd rect
			(at 2.050034 -58.224928 90)
			(size 0.519938 1.4986)
			(layers "F.Cu" "F.Mask" "F.Paste")
			(net "GND")
		)
		(pad "152" smd rect
			(at 2.050034 -57.375044 90)
			(size 0.519938 1.4986)
			(layers "F.Cu" "F.Mask" "F.Paste")
			(net "M_J_CPU0_SA_DQ<2>")
		)
		(pad "153" smd rect
			(at 2.050034 -56.524906 90)
			(size 0.519938 1.4986)
			(layers "F.Cu" "F.Mask" "F.Paste")
			(net "GND")
		)
		(pad "154" smd rect
			(at 2.050034 -55.675022 90)
			(size 0.519938 1.4986)
			(layers "F.Cu" "F.Mask" "F.Paste")
			(net "M_J_CPU0_SA_DQ<3>")
		)
		(pad "155" smd rect
			(at 2.050034 -54.824884 90)
			(size 0.519938 1.4986)
			(layers "F.Cu" "F.Mask" "F.Paste")
			(net "GND")
		)
		(pad "156" smd rect
			(at 2.050034 -53.975 90)
			(size 0.519938 1.4986)
			(layers "F.Cu" "F.Mask" "F.Paste")
			(net "M_J_CPU0_SA_DQS_DN<5>")
		)
		(pad "157" smd rect
			(at 2.050034 -53.125116 90)
			(size 0.519938 1.4986)
			(layers "F.Cu" "F.Mask" "F.Paste")
			(net "M_J_CPU0_SA_DQS_DP<5>")
		)
		(pad "158" smd rect
			(at 2.050034 -52.274978 90)
			(size 0.519938 1.4986)
			(layers "F.Cu" "F.Mask" "F.Paste")
			(net "GND")
		)
		(pad "159" smd rect
			(at 2.050034 -51.425094 90)
			(size 0.519938 1.4986)
			(layers "F.Cu" "F.Mask" "F.Paste")
			(net "M_J_CPU0_SA_DQ<6>")
		)
		(pad "160" smd rect
			(at 2.050034 -50.574956 90)
			(size 0.519938 1.4986)
			(layers "F.Cu" "F.Mask" "F.Paste")
			(net "GND")
		)
		(pad "161" smd rect
			(at 2.050034 -49.725072 90)
			(size 0.519938 1.4986)
			(layers "F.Cu" "F.Mask" "F.Paste")
			(net "M_J_CPU0_SA_DQ<7>")
		)
		(pad "162" smd rect
			(at 2.050034 -48.874934 90)
			(size 0.519938 1.4986)
			(layers "F.Cu" "F.Mask" "F.Paste")
			(net "GND")
		)
		(pad "163" smd rect
			(at 2.050034 -48.02505 90)
			(size 0.519938 1.4986)
			(layers "F.Cu" "F.Mask" "F.Paste")
			(net "M_J_CPU0_SA_DQ<10>")
		)
		(pad "164" smd rect
			(at 2.050034 -47.174912 90)
			(size 0.519938 1.4986)
			(layers "F.Cu" "F.Mask" "F.Paste")
			(net "GND")
		)
		(pad "165" smd rect
			(at 2.050034 -46.325028 90)
			(size 0.519938 1.4986)
			(layers "F.Cu" "F.Mask" "F.Paste")
			(net "M_J_CPU0_SA_DQ<11>")
		)
		(pad "166" smd rect
			(at 2.050034 -45.47489 90)
			(size 0.519938 1.4986)
			(layers "F.Cu" "F.Mask" "F.Paste")
			(net "GND")
		)
		(pad "167" smd rect
			(at 2.050034 -44.625006 90)
			(size 0.519938 1.4986)
			(layers "F.Cu" "F.Mask" "F.Paste")
			(net "M_J_CPU0_SA_DQS_DN<6>")
		)
		(pad "168" smd rect
			(at 2.050034 -43.775122 90)
			(size 0.519938 1.4986)
			(layers "F.Cu" "F.Mask" "F.Paste")
			(net "M_J_CPU0_SA_DQS_DP<6>")
		)
		(pad "169" smd rect
			(at 2.050034 -42.924984 90)
			(size 0.519938 1.4986)
			(layers "F.Cu" "F.Mask" "F.Paste")
			(net "GND")
		)
		(pad "170" smd rect
			(at 2.050034 -42.0751 90)
			(size 0.519938 1.4986)
			(layers "F.Cu" "F.Mask" "F.Paste")
			(net "M_J_CPU0_SA_DQ<14>")
		)
		(pad "171" smd rect
			(at 2.050034 -41.224962 90)
			(size 0.519938 1.4986)
			(layers "F.Cu" "F.Mask" "F.Paste")
			(net "GND")
		)
		(pad "172" smd rect
			(at 2.050034 -40.375078 90)
			(size 0.519938 1.4986)
			(layers "F.Cu" "F.Mask" "F.Paste")
			(net "M_J_CPU0_SA_DQ<15>")
		)
		(pad "173" smd rect
			(at 2.050034 -39.52494 90)
			(size 0.519938 1.4986)
			(layers "F.Cu" "F.Mask" "F.Paste")
			(net "GND")
		)
		(pad "174" smd rect
			(at 2.050034 -38.675056 90)
			(size 0.519938 1.4986)
			(layers "F.Cu" "F.Mask" "F.Paste")
			(net "M_J_CPU0_SA_DQ<18>")
		)
		(pad "175" smd rect
			(at 2.050034 -37.824918 90)
			(size 0.519938 1.4986)
			(layers "F.Cu" "F.Mask" "F.Paste")
			(net "GND")
		)
		(pad "176" smd rect
			(at 2.050034 -36.975034 90)
			(size 0.519938 1.4986)
			(layers "F.Cu" "F.Mask" "F.Paste")
			(net "M_J_CPU0_SA_DQ<19>")
		)
		(pad "177" smd rect
			(at 2.050034 -36.124896 90)
			(size 0.519938 1.4986)
			(layers "F.Cu" "F.Mask" "F.Paste")
			(net "GND")
		)
		(pad "178" smd rect
			(at 2.050034 -35.275012 90)
			(size 0.519938 1.4986)
			(layers "F.Cu" "F.Mask" "F.Paste")
			(net "M_J_CPU0_SA_DQS_DN<7>")
		)
		(pad "179" smd rect
			(at 2.050034 -34.425128 90)
			(size 0.519938 1.4986)
			(layers "F.Cu" "F.Mask" "F.Paste")
			(net "M_J_CPU0_SA_DQS_DP<7>")
		)
		(pad "180" smd rect
			(at 2.050034 -33.57499 90)
			(size 0.519938 1.4986)
			(layers "F.Cu" "F.Mask" "F.Paste")
			(net "GND")
		)
		(pad "181" smd rect
			(at 2.050034 -32.725106 90)
			(size 0.519938 1.4986)
			(layers "F.Cu" "F.Mask" "F.Paste")
			(net "M_J_CPU0_SA_DQ<22>")
		)
		(pad "182" smd rect
			(at 2.050034 -31.874968 90)
			(size 0.519938 1.4986)
			(layers "F.Cu" "F.Mask" "F.Paste")
			(net "GND")
		)
		(pad "183" smd rect
			(at 2.050034 -31.025084 90)
			(size 0.519938 1.4986)
			(layers "F.Cu" "F.Mask" "F.Paste")
			(net "M_J_CPU0_SA_DQ<23>")
		)
		(pad "184" smd rect
			(at 2.050034 -30.174946 90)
			(size 0.519938 1.4986)
			(layers "F.Cu" "F.Mask" "F.Paste")
			(net "GND")
		)
		(pad "185" smd rect
			(at 2.050034 -29.325062 90)
			(size 0.519938 1.4986)
			(layers "F.Cu" "F.Mask" "F.Paste")
			(net "M_J_CPU0_SA_DQ<26>")
		)
		(pad "186" smd rect
			(at 2.050034 -28.474924 90)
			(size 0.519938 1.4986)
			(layers "F.Cu" "F.Mask" "F.Paste")
			(net "GND")
		)
		(pad "187" smd rect
			(at 2.050034 -27.62504 90)
			(size 0.519938 1.4986)
			(layers "F.Cu" "F.Mask" "F.Paste")
			(net "M_J_CPU0_SA_DQ<27>")
		)
		(pad "188" smd rect
			(at 2.050034 -26.774902 90)
			(size 0.519938 1.4986)
			(layers "F.Cu" "F.Mask" "F.Paste")
			(net "GND")
		)
		(pad "189" smd rect
			(at 2.050034 -25.925018 90)
			(size 0.519938 1.4986)
			(layers "F.Cu" "F.Mask" "F.Paste")
			(net "M_J_CPU0_SA_DQS_DN<8>")
		)
		(pad "190" smd rect
			(at 2.050034 -25.07488 90)
			(size 0.519938 1.4986)
			(layers "F.Cu" "F.Mask" "F.Paste")
			(net "M_J_CPU0_SA_DQS_DP<8>")
		)
		(pad "191" smd rect
			(at 2.050034 -24.224996 90)
			(size 0.519938 1.4986)
			(layers "F.Cu" "F.Mask" "F.Paste")
			(net "GND")
		)
		(pad "192" smd rect
			(at 2.050034 -23.375112 90)
			(size 0.519938 1.4986)
			(layers "F.Cu" "F.Mask" "F.Paste")
			(net "M_J_CPU0_SA_DQ<30>")
		)
		(pad "193" smd rect
			(at 2.050034 -22.524974 90)
			(size 0.519938 1.4986)
			(layers "F.Cu" "F.Mask" "F.Paste")
			(net "GND")
		)
		(pad "194" smd rect
			(at 2.050034 -21.67509 90)
			(size 0.519938 1.4986)
			(layers "F.Cu" "F.Mask" "F.Paste")
			(net "M_J_CPU0_SA_DQ<31>")
		)
		(pad "195" smd rect
			(at 2.050034 -20.824952 90)
			(size 0.519938 1.4986)
			(layers "F.Cu" "F.Mask" "F.Paste")
			(net "GND")
		)
		(pad "196" smd rect
			(at 2.050034 -19.975068 90)
			(size 0.519938 1.4986)
			(layers "F.Cu" "F.Mask" "F.Paste")
			(net "M_J_CPU0_SA_CB<2>")
		)
		(pad "197" smd rect
			(at 2.050034 -19.12493 90)
			(size 0.519938 1.4986)
			(layers "F.Cu" "F.Mask" "F.Paste")
			(net "GND")
		)
		(pad "198" smd rect
			(at 2.050034 -18.275046 90)
			(size 0.519938 1.4986)
			(layers "F.Cu" "F.Mask" "F.Paste")
			(net "M_J_CPU0_SA_CB<3>")
		)
		(pad "199" smd rect
			(at 2.050034 -17.424908 90)
			(size 0.519938 1.4986)
			(layers "F.Cu" "F.Mask" "F.Paste")
			(net "GND")
		)
		(pad "200" smd rect
			(at 2.050034 -16.575024 90)
			(size 0.519938 1.4986)
			(layers "F.Cu" "F.Mask" "F.Paste")
			(net "M_J_CPU0_SA_DQS_DN<9>")
		)
		(pad "201" smd rect
			(at 2.050034 -15.724886 90)
			(size 0.519938 1.4986)
			(layers "F.Cu" "F.Mask" "F.Paste")
			(net "M_J_CPU0_SA_DQS_DP<9>")
		)
		(pad "202" smd rect
			(at 2.050034 -14.875002 90)
			(size 0.519938 1.4986)
			(layers "F.Cu" "F.Mask" "F.Paste")
			(net "GND")
		)
		(pad "203" smd rect
			(at 2.050034 -14.025118 90)
			(size 0.519938 1.4986)
			(layers "F.Cu" "F.Mask" "F.Paste")
			(net "M_J_CPU0_SA_CB<6>")
		)
		(pad "204" smd rect
			(at 2.050034 -13.17498 90)
			(size 0.519938 1.4986)
			(layers "F.Cu" "F.Mask" "F.Paste")
			(net "GND")
		)
		(pad "205" smd rect
			(at 2.050034 -12.325096 90)
			(size 0.519938 1.4986)
			(layers "F.Cu" "F.Mask" "F.Paste")
			(net "M_J_CPU0_SA_CB<7>")
		)
		(pad "206" smd rect
			(at 2.050034 -11.474958 90)
			(size 0.519938 1.4986)
			(layers "F.Cu" "F.Mask" "F.Paste")
			(net "GND")
		)
		(pad "207" smd rect
			(at 2.050034 -10.625074 90)
			(size 0.519938 1.4986)
			(layers "F.Cu" "F.Mask" "F.Paste")
			(net "M_J_CPU0_RESET_N")
		)
		(pad "208" smd rect
			(at 2.050034 -9.774936 90)
			(size 0.519938 1.4986)
			(layers "F.Cu" "F.Mask" "F.Paste")
			(net "GND")
		)
		(pad "209" smd rect
			(at 2.050034 -8.925052 90)
			(size 0.519938 1.4986)
			(layers "F.Cu" "F.Mask" "F.Paste")
			(net "M_J_CPU0_SA_CS_N<1>")
		)
		(pad "210" smd rect
			(at 2.050034 -8.074914 90)
			(size 0.519938 1.4986)
			(layers "F.Cu" "F.Mask" "F.Paste")
			(net "GND")
		)
		(pad "211" smd rect
			(at 2.050034 -7.22503 90)
			(size 0.519938 1.4986)
			(layers "F.Cu" "F.Mask" "F.Paste")
			(net "M_J_CPU0_SA_CA<1>")
		)
		(pad "212" smd rect
			(at 2.050034 -6.374892 90)
			(size 0.519938 1.4986)
			(layers "F.Cu" "F.Mask" "F.Paste")
			(net "GND")
		)
		(pad "213" smd rect
			(at 2.050034 -5.525008 90)
			(size 0.519938 1.4986)
			(layers "F.Cu" "F.Mask" "F.Paste")
			(net "M_J_CPU0_SA_CA<3>")
		)
		(pad "214" smd rect
			(at 2.050034 -4.675124 90)
			(size 0.519938 1.4986)
			(layers "F.Cu" "F.Mask" "F.Paste")
			(net "GND")
		)
		(pad "215" smd rect
			(at 2.050034 -3.824986 90)
			(size 0.519938 1.4986)
			(layers "F.Cu" "F.Mask" "F.Paste")
			(net "M_J_CPU0_SA_CA<5>")
		)
		(pad "216" smd rect
			(at 2.050034 -2.975102 90)
			(size 0.519938 1.4986)
			(layers "F.Cu" "F.Mask" "F.Paste")
			(net "GND")
		)
		(pad "217" smd rect
			(at 2.050034 -2.124964 90)
			(size 0.519938 1.4986)
			(layers "F.Cu" "F.Mask" "F.Paste")
			(net "M_J_CPU0_CLK_DP<0>")
		)
		(pad "218" smd rect
			(at 2.050034 -1.27508 90)
			(size 0.519938 1.4986)
			(layers "F.Cu" "F.Mask" "F.Paste")
			(net "M_J_CPU0_CLK_DN<0>")
		)
		(pad "219" smd rect
			(at 2.050034 -0.424942 90)
			(size 0.519938 1.4986)
			(layers "F.Cu" "F.Mask" "F.Paste")
			(net "GND")
		)
		(pad "220" smd rect
			(at 2.050034 5.525008 90)
			(size 0.519938 1.4986)
			(layers "F.Cu" "F.Mask" "F.Paste")
			(net "Net_2379")
		)
		(pad "221" smd rect
			(at 2.050034 6.374892 90)
			(size 0.519938 1.4986)
			(layers "F.Cu" "F.Mask" "F.Paste")
			(net "M_J_CPU0_SB_CA<1>")
		)
		(pad "222" smd rect
			(at 2.050034 7.22503 90)
			(size 0.519938 1.4986)
			(layers "F.Cu" "F.Mask" "F.Paste")
			(net "GND")
		)
		(pad "223" smd rect
			(at 2.050034 8.074914 90)
			(size 0.519938 1.4986)
			(layers "F.Cu" "F.Mask" "F.Paste")
			(net "M_J_CPU0_SB_CA<3>")
		)
		(pad "224" smd rect
			(at 2.050034 8.925052 90)
			(size 0.519938 1.4986)
			(layers "F.Cu" "F.Mask" "F.Paste")
			(net "GND")
		)
		(pad "225" smd rect
			(at 2.050034 9.774936 90)
			(size 0.519938 1.4986)
			(layers "F.Cu" "F.Mask" "F.Paste")
			(net "M_J_CPU0_SB_CA<5>")
		)
		(pad "226" smd rect
			(at 2.050034 10.625074 90)
			(size 0.519938 1.4986)
			(layers "F.Cu" "F.Mask" "F.Paste")
			(net "GND")
		)
	)
)
